# T6G (Grand Teton) — schematic netlist excerpt (pin names and nets, part order shuffled) for the footprints in the layout excerpt that follows; sources: Cadence DE-HDL packaged netlist, KiCad conversion of 04192023_DAF0TMB3IC0_F0TG_MB_C_brd_V02_OCP.brd

C2287  Q_CAP  22UF 4V 20% X6S  pkg C0402  page 72 : A = PVDD11_S3_P1 ; B = GND
C6561  Q_CAP_DIFFBUS  DIFF BUS_0.22UF 6.3V 20% X6S  pkg C0201  page 286 : \1\ = P5E_CPU0_P1_TX_BUF_C_DP<14> ; \2\ = P5E_CPU0_P1_TX_BUF_DP<14>
R9000  Q_RES  1K 1% CHIP  pkg 0402LF  page 240 : A = P3V3_AUX ; B = FM_FAN_PWR_EN

(kicad_pcb
	(version 20260206)
	(generator "pcbnew")
	(generator_version "10.0")
	(general
		(thickness 1.6)
		(legacy_teardrops no)
	)
	(paper "A4")
	(title_block
		(title "04192023_DAF0TMB3IC0_F0TG_MB_C_brd_V02_OCP.brd")
		(comment 1 "Grand Teton / footprints 6746-6748 of 8354")
	)
	(layers
		(0 "F.Cu" signal "TOP")
		(4 "In1.Cu" signal "GND")
		(6 "In2.Cu" signal "IN1")
		(8 "In3.Cu" signal "GND1")
		(10 "In4.Cu" signal "IN2")
		(12 "In5.Cu" signal "GND2")
		(14 "In6.Cu" signal "IN3")
		(16 "In7.Cu" signal "GND3")
		(18 "In8.Cu" signal "VCC")
		(20 "In9.Cu" signal "VCC1")
		(22 "In10.Cu" signal "GND4")
		(24 "In11.Cu" signal "IN4")
		(26 "In12.Cu" signal "GND5")
		(28 "In13.Cu" signal "IN5")
		(30 "In14.Cu" signal "GND6")
		(32 "In15.Cu" signal "IN6")
		(34 "In16.Cu" signal "GND7")
		(2 "B.Cu" signal "BOTTOM")
		(9 "F.Adhes" user "F.Adhesive")
		(11 "B.Adhes" user "B.Adhesive")
		(13 "F.Paste" user "Package Geometry/Pastemask Top")
		(15 "B.Paste" user "Package Geometry/Pastemask Bottom")
		(5 "F.SilkS" user "Ref Des/Silkscreen Top")
		(7 "B.SilkS" user "Ref Des/Silkscreen Bottom")
		(1 "F.Mask" user "Board Geometry/Soldermask Top")
		(3 "B.Mask" user "Board Geometry/Soldermask Bottom")
		(17 "Dwgs.User" user "User.Drawings")
		(19 "Cmts.User" user "User.Comments")
		(21 "Eco1.User" user "User.Eco1")
		(23 "Eco2.User" user "User.Eco2")
		(25 "Edge.Cuts" user "Board Geometry/Outline")
		(27 "Margin" user)
		(31 "F.CrtYd" user "Package Geometry/Place Bound Top")
		(29 "B.CrtYd" user "Package Geometry/Place Bound Bottom")
		(35 "F.Fab" user "Ref Des/Assembly Top")
		(33 "B.Fab" user "Ref Des/Assembly Bottom")
	)
	(footprint ""
		(layer "B.Cu")
		(at 106.466386 -266.005564)
		(property "Reference" "C2287"
			(at 0 0 0)
			(layer "B.SilkS")
			(hide yes)
			(effects
				(font
					(size 1.27 1.27)
				)
				(justify mirror)
			)
		)
		(property "Value" ""
			(at 0 0 0)
			(layer "B.Fab")
			(effects
				(font
					(size 1.27 1.27)
				)
				(justify mirror)
			)
		)
		(duplicate_pad_numbers_are_jumpers no)
		(fp_line
			(start -0.7874 -0.4064)
			(end -0.7874 0.4064)
			(stroke
				(width 0.1524)
				(type default)
			)
			(layer "B.SilkS")
		)
		(fp_line
			(start -0.7874 0.4064)
			(end 0.7874 0.4064)
			(stroke
				(width 0.1524)
				(type default)
			)
			(layer "B.SilkS")
		)
		(fp_line
			(start 0.7874 -0.4064)
			(end -0.7874 -0.4064)
			(stroke
				(width 0.1524)
				(type default)
			)
			(layer "B.SilkS")
		)
		(fp_line
			(start 0.7874 0.4064)
			(end 0.7874 -0.4064)
			(stroke
				(width 0.1524)
				(type default)
			)
			(layer "B.SilkS")
		)
		(fp_line
			(start -0.67945 -0.3048)
			(end -0.67945 0.3048)
			(stroke
				(width 0.1)
				(type default)
			)
			(layer "B.Fab")
		)
		(fp_line
			(start -0.67945 0.3048)
			(end -0.120396 0.3048)
			(stroke
				(width 0.1)
				(type default)
			)
			(layer "B.Fab")
		)
		(fp_line
			(start -0.12065 -0.3048)
			(end -0.67945 -0.3048)
			(stroke
				(width 0.1)
				(type default)
			)
			(layer "B.Fab")
		)
		(fp_line
			(start -0.12065 -0.2794)
			(end -0.12065 -0.3048)
			(stroke
				(width 0.1)
				(type default)
			)
			(layer "B.Fab")
		)
		(fp_line
			(start -0.120396 0.2794)
			(end 0.12065 0.2794)
			(stroke
				(width 0.1)
				(type default)
			)
			(layer "B.Fab")
		)
		(fp_line
			(start -0.120396 0.3048)
			(end -0.120396 0.2794)
			(stroke
				(width 0.1)
				(type default)
			)
			(layer "B.Fab")
		)
		(fp_line
			(start 0.12065 -0.305054)
			(end 0.12065 -0.2794)
			(stroke
				(width 0.1)
				(type default)
			)
			(layer "B.Fab")
		)
		(fp_line
			(start 0.12065 -0.2794)
			(end -0.12065 -0.2794)
			(stroke
				(width 0.1)
				(type default)
			)
			(layer "B.Fab")
		)
		(fp_line
			(start 0.12065 0.2794)
			(end 0.12065 0.3048)
			(stroke
				(width 0.1)
				(type default)
			)
			(layer "B.Fab")
		)
		(fp_line
			(start 0.12065 0.3048)
			(end 0.67945 0.3048)
			(stroke
				(width 0.1)
				(type default)
			)
			(layer "B.Fab")
		)
		(fp_line
			(start 0.67945 -0.305054)
			(end 0.12065 -0.305054)
			(stroke
				(width 0.1)
				(type default)
			)
			(layer "B.Fab")
		)
		(fp_line
			(start 0.67945 0.3048)
			(end 0.67945 -0.305054)
			(stroke
				(width 0.1)
				(type default)
			)
			(layer "B.Fab")
		)
		(pad "1" smd circle
			(at 0.40005 0 180)
			(size 0 0)
			(layers "B.Cu" "B.Mask" "B.Paste")
			(net "PVDD11_S3_P1")
		)
		(pad "2" smd circle
			(at -0.40005 0 180)
			(size 0 0)
			(layers "B.Cu" "B.Mask" "B.Paste")
			(net "GND")
		)
	)
	(footprint ""
		(layer "B.Cu")
		(at 241.756692 -420.80688 -90)
		(property "Reference" "R9000"
			(at 0 0 90)
			(layer "B.SilkS")
			(hide yes)
			(effects
				(font
					(size 1.27 1.27)
				)
				(justify mirror)
			)
		)
		(property "Value" ""
			(at 0 0 90)
			(layer "B.Fab")
			(effects
				(font
					(size 1.27 1.27)
				)
				(justify mirror)
			)
		)
		(duplicate_pad_numbers_are_jumpers no)
		(fp_line
			(start -0.7874 0.4064)
			(end 0.7874 0.4064)
			(stroke
				(width 0.1524)
				(type default)
			)
			(layer "B.SilkS")
		)
		(fp_line
			(start 0.7874 0.4064)
			(end 0.7874 -0.4064)
			(stroke
				(width 0.1524)
				(type default)
			)
			(layer "B.SilkS")
		)
		(fp_line
			(start -0.7874 -0.4064)
			(end -0.7874 0.4064)
			(stroke
				(width 0.1524)
				(type default)
			)
			(layer "B.SilkS")
		)
		(fp_line
			(start 0.7874 -0.4064)
			(end -0.7874 -0.4064)
			(stroke
				(width 0.1524)
				(type default)
			)
			(layer "B.SilkS")
		)
		(fp_line
			(start -0.67945 0.3048)
			(end -0.120396 0.3048)
			(stroke
				(width 0.1)
				(type default)
			)
			(layer "B.Fab")
		)
		(fp_line
			(start -0.120396 0.3048)
			(end -0.120396 0.2794)
			(stroke
				(width 0.1)
				(type default)
			)
			(layer "B.Fab")
		)
		(fp_line
			(start 0.12065 0.3048)
			(end 0.67945 0.3048)
			(stroke
				(width 0.1)
				(type default)
			)
			(layer "B.Fab")
		)
		(fp_line
			(start 0.67945 0.3048)
			(end 0.67945 -0.305054)
			(stroke
				(width 0.1)
				(type default)
			)
			(layer "B.Fab")
		)
		(fp_line
			(start -0.120396 0.2794)
			(end 0.12065 0.2794)
			(stroke
				(width 0.1)
				(type default)
			)
			(layer "B.Fab")
		)
		(fp_line
			(start 0.12065 0.2794)
			(end 0.12065 0.3048)
			(stroke
				(width 0.1)
				(type default)
			)
			(layer "B.Fab")
		)
		(fp_line
			(start -0.12065 -0.2794)
			(end -0.12065 -0.3048)
			(stroke
				(width 0.1)
				(type default)
			)
			(layer "B.Fab")
		)
		(fp_line
			(start 0.12065 -0.2794)
			(end -0.12065 -0.2794)
			(stroke
				(width 0.1)
				(type default)
			)
			(layer "B.Fab")
		)
		(fp_line
			(start -0.67945 -0.3048)
			(end -0.67945 0.3048)
			(stroke
				(width 0.1)
				(type default)
			)
			(layer "B.Fab")
		)
		(fp_line
			(start -0.12065 -0.3048)
			(end -0.67945 -0.3048)
			(stroke
				(width 0.1)
				(type default)
			)
			(layer "B.Fab")
		)
		(fp_line
			(start 0.12065 -0.305054)
			(end 0.12065 -0.2794)
			(stroke
				(width 0.1)
				(type default)
			)
			(layer "B.Fab")
		)
		(fp_line
			(start 0.67945 -0.305054)
			(end 0.12065 -0.305054)
			(stroke
				(width 0.1)
				(type default)
			)
			(layer "B.Fab")
		)
		(pad "1" smd circle
			(at 0.40005 0 90)
			(size 0 0)
			(layers "B.Cu" "B.Mask" "B.Paste")
			(net "P3V3_AUX")
		)
		(pad "2" smd circle
			(at -0.40005 0 90)
			(size 0 0)
			(layers "B.Cu" "B.Mask" "B.Paste")
			(net "FM_FAN_PWR_EN")
		)
	)
	(footprint ""
		(layer "B.Cu")
		(at 349.099886 -416.899344 90)
		(property "Reference" "C6561"
			(at 0 0 90)
			(layer "B.SilkS")
			(hide yes)
			(effects
				(font
					(size 1.27 1.27)
				)
				(justify mirror)
			)
		)
		(property "Value" ""
			(at 0 0 90)
			(layer "B.Fab")
			(effects
				(font
					(size 1.27 1.27)
				)
				(justify mirror)
			)
		)
		(duplicate_pad_numbers_are_jumpers no)
		(fp_line
			(start 0.299974 -0.150114)
			(end -0.299974 -0.150114)
			(stroke
				(width 0.1)
				(type default)
			)
			(layer "B.Fab")
		)
		(fp_line
			(start -0.299974 -0.150114)
			(end -0.299974 0.150114)
			(stroke
				(width 0.1)
				(type default)
			)
			(layer "B.Fab")
		)
		(fp_line
			(start 0.299974 0.150114)
			(end 0.299974 -0.150114)
			(stroke
				(width 0.1)
				(type default)
			)
			(layer "B.Fab")
		)
		(fp_line
			(start -0.299974 0.150114)
			(end 0.299974 0.150114)
			(stroke
				(width 0.1)
				(type default)
			)
			(layer "B.Fab")
		)
		(pad "1" smd rect
			(at 0.2667 0 270)
			(size 0.3048 0.381)
			(layers "B.Cu" "B.Mask" "B.Paste")
			(net "P5E_CPU0_P1_TX_BUF_C_DP<14>")
		)
		(pad "2" smd rect
			(at -0.2667 0 270)
			(size 0.3048 0.381)
			(layers "B.Cu" "B.Mask" "B.Paste")
			(net "P5E_CPU0_P1_TX_BUF_DP<14>")
		)
	)
)
